# S9S_MB_2U (Grand Teton) — schematic netlist excerpt (pin names and nets, part order shuffled) for the footprints in the layout excerpt that follows; sources: Cadence DE-HDL packaged netlist, KiCad conversion of 03242023_DA0F0TMBIJ0_F0T_Motherboard_J_brd_V01_OCP.brd

J29  SCONN288_ADR50017P130CC  SCONN288_ADR50017-P130CC IO  pkg DDR288S_1-1VXB  page 110
  VIN_BULK0  = P12V_S3_AUX_CPU1_NVDIMM
  RFU0  = TP_CHG_CPU1_DIMM1_FRU_0
  VIN_MGMT  = P3V3_AUX
  HSCL  = I3C_SPD_DDREFGH_CPU1_LVC1_SCL_4
  HSDA  = I3C_SPD_DDREFGH_CPU1_LVC1_SDA
  VSS0  = GND
  DQ0_A  = M_G_CPU1_SA_DQ<0>
  VSS1  = GND
  DQ1_A  = M_G_CPU1_SA_DQ<1>
  VSS2  = GND
  DQS0_A_T  = M_G_CPU1_SA_DQS_DP<0>
  DQS0_A_C  = M_G_CPU1_SA_DQS_DN<0>
  VSS3  = GND
  DQ4_A  = M_G_CPU1_SA_DQ<4>
  VSS4  = GND
  DQ5_A  = M_G_CPU1_SA_DQ<5>
  VSS5  = GND
  DQ8_A  = M_G_CPU1_SA_DQ<8>
  VSS6  = GND
  DQ9_A  = M_G_CPU1_SA_DQ<9>
  VSS7  = GND
  DQS1_A_T  = M_G_CPU1_SA_DQS_DP<1>
  DQS1_A_C  = M_G_CPU1_SA_DQS_DN<1>
  VSS8  = GND
  DQ12_A  = M_G_CPU1_SA_DQ<12>
  VSS9  = GND
  DQ13_A  = M_G_CPU1_SA_DQ<13>
  VSS10  = GND
  DQ16_A  = M_G_CPU1_SA_DQ<16>
  VSS11  = GND
  DQ17_A  = M_G_CPU1_SA_DQ<17>
  VSS12  = GND
  DQS2_A_T  = M_G_CPU1_SA_DQS_DP<2>
  DQS2_A_C  = M_G_CPU1_SA_DQS_DN<2>
  VSS13  = GND
  DQ20_A  = M_G_CPU1_SA_DQ<20>
  VSS14  = GND
  DQ21_A  = M_G_CPU1_SA_DQ<21>
  VSS15  = GND
  DQ24_A  = M_G_CPU1_SA_DQ<24>
  VSS16  = GND
  DQ25_A  = M_G_CPU1_SA_DQ<25>
  VSS17  = GND
  DQS3_A_T  = M_G_CPU1_SA_DQS_DP<3>
  DQS3_A_C  = M_G_CPU1_SA_DQS_DN<3>
  VSS18  = GND
  DQ28_A  = M_G_CPU1_SA_DQ<28>
  VSS19  = GND
  DQ29_A  = M_G_CPU1_SA_DQ<29>
  VSS20  = GND
  CB0_A  = M_G_CPU1_SA_CB<0>
  VSS21  = GND
  CB1_A  = M_G_CPU1_SA_CB<1>
  VSS22  = GND
  DQS4_A_T  = M_G_CPU1_SA_DQS_DP<4>
  DQS4_A_C  = M_G_CPU1_SA_DQS_DN<4>
  VSS23  = GND
  CB4_A  = M_G_CPU1_SA_CB<4>
  VSS24  = GND
  CB5_A  = M_G_CPU1_SA_CB<5>
  VSS25  = GND
  ALERT_N  = M_G_CPU1_ALERT_N
  VSS26  = GND
  CS0_A_N  = M_G_CPU1_SA_CS_N<0>
  VSS27  = GND
  CA0_A  = M_G_CPU1_SA_CA<0>
  VSS28  = GND
  CA2_A  = M_G_CPU1_SA_CA<2>
  VSS29  = GND
  CA4_A  = M_G_CPU1_SA_CA<4>
  VSS30  = GND
  CA6_A  = M_G_CPU1_SA_CA<6>
  VSS31  = GND
  PAR_A  = M_G_CPU1_SA_PAR
  VSS32  = GND
  CA0_B  = M_G_CPU1_SB_CA<0>
  VSS33  = GND
  CA2_B  = M_G_CPU1_SB_CA<2>
  VSS34  = GND
  CA4_B  = M_G_CPU1_SB_CA<4>
  VSS35  = GND
  CA6_B  = M_G_CPU1_SB_CA<6>
  VSS36  = GND
  CS0_B_N  = M_G_CPU1_SB_CS_N<0>
  VSS37  = GND
  \lbd||rsp_a_n\  = M_G_CPU1_SA_RSP<0>
  \lbs||rsp_b_n\  = M_G_CPU1_SB_RSP<0>
  VSS38  = GND
  CB4_B  = M_G_CPU1_SB_CB<4>
  VSS39  = GND
  CB5_B  = M_G_CPU1_SB_CB<5>
  VSS40  = GND
  \dqs9_b_t||tdqs9_b_t||dbi4_b_n\  = M_G_CPU1_SB_DQS_DP<9>
  \dqs9_b_c||tdqs9_b_c\  = M_G_CPU1_SB_DQS_DN<9>
  VSS41  = GND
  CB0_B  = M_G_CPU1_SB_CB<0>
  VSS42  = GND
  CB1_B  = M_G_CPU1_SB_CB<1>
  VSS43  = GND
  DQ0_B  = M_G_CPU1_SB_DQ<0>
  VSS44  = GND
  DQ1_B  = M_G_CPU1_SB_DQ<1>
  VSS45  = GND
  DQS0_B_T  = M_G_CPU1_SB_DQS_DP<0>
  DQS0_B_C  = M_G_CPU1_SB_DQS_DN<0>
  VSS46  = GND
  DQ4_B  = M_G_CPU1_SB_DQ<4>
  VSS47  = GND
  DQ5_B  = M_G_CPU1_SB_DQ<5>
  VSS48  = GND
  DQ8_B  = M_G_CPU1_SB_DQ<8>
  VSS49  = GND
  DQ9_B  = M_G_CPU1_SB_DQ<9>
  VSS50  = GND
  DQS1_B_T  = M_G_CPU1_SB_DQS_DP<1>
  DQS1_B_C  = M_G_CPU1_SB_DQS_DN<1>
  VSS51  = GND
  DQ12_B  = M_G_CPU1_SB_DQ<12>
  VSS52  = GND
  DQ13_B  = M_G_CPU1_SB_DQ<13>
  VSS53  = GND
  DQ16_B  = M_G_CPU1_SB_DQ<16>
  VSS54  = GND
  DQ17_B  = M_G_CPU1_SB_DQ<17>
  VSS55  = GND
  DQS2_B_T  = M_G_CPU1_SB_DQS_DP<2>
  DQS2_B_C  = M_G_CPU1_SB_DQS_DN<2>
  VSS56  = GND
  DQ20_B  = M_G_CPU1_SB_DQ<20>
  VSS57  = GND
  DQ21_B  = M_G_CPU1_SB_DQ<21>
  VSS58  = GND
  DQ24_B  = M_G_CPU1_SB_DQ<24>
  VSS59  = GND
  DQ25_B  = M_G_CPU1_SB_DQ<25>
  VSS60  = GND
  DQS3_B_T  = M_G_CPU1_SB_DQS_DP<3>
  DQS3_B_C  = M_G_CPU1_SB_DQS_DN<3>
  VSS61  = GND
  DQ28_B  = M_G_CPU1_SB_DQ<28>
  VSS62  = GND
  DQ29_B  = M_G_CPU1_SB_DQ<29>
  VSS63  = GND
  RFU1  = TP_CHG_CPU1_DIMM1_FRU_1
  VIN_BULK1  = P12V_S3_AUX_CPU1_NVDIMM
  VIN_BULK2  = P12V_S3_AUX_CPU1_NVDIMM
  \pwr_good||fail_n\  = PWRGD_CHG_CPU1_DIMM1
  HSA  = PD_CHG_CPU1_DIMM1_SAA
  RFU2  = TP_CHG_CPU1_DIMM1_FRU_2
  RFU3  = TP_CHG_CPU1_DIMM1_FRU_3
  VSS64  = GND
  DQ2_A  = M_G_CPU1_SA_DQ<2>
  VSS65  = GND
  DQ3_A  = M_G_CPU1_SA_DQ<3>
  VSS66  = GND
  \dqs5_a_c||tdqs5_a_c||dqs5_a_t||tdqs5_a_t\  = M_G_CPU1_SA_DQS_DN<5>
  \dqs5_a_t||tdqs5_a_t\  = M_G_CPU1_SA_DQS_DP<5>
  VSS67  = GND
  DQ6_A  = M_G_CPU1_SA_DQ<6>
  VSS68  = GND
  DQ7_A  = M_G_CPU1_SA_DQ<7>
  VSS69  = GND
  DQ10_A  = M_G_CPU1_SA_DQ<10>
  VSS70  = GND
  DQ11_A  = M_G_CPU1_SA_DQ<11>
  VSS71  = GND
  \dqs6_a_c||tdqs6_a_c||dqs6_a_t||tdqs6_a_t\  = M_G_CPU1_SA_DQS_DN<6>
  \dqs6_a_t||tdqs6_a_t\  = M_G_CPU1_SA_DQS_DP<6>
  VSS72  = GND
  DQ14_A  = M_G_CPU1_SA_DQ<14>
  VSS73  = GND
  DQ15_A  = M_G_CPU1_SA_DQ<15>
  VSS74  = GND
  DQ18_A  = M_G_CPU1_SA_DQ<18>
  VSS75  = GND
  DQ19_A  = M_G_CPU1_SA_DQ<19>
  VSS76  = GND
  \dqs7_a_c||tdqs7_a_c\  = M_G_CPU1_SA_DQS_DN<7>
  \dqs7_a_t||tdqs7_a_t\  = M_G_CPU1_SA_DQS_DP<7>
  VSS77  = GND
  DQ22_A  = M_G_CPU1_SA_DQ<22>
  VSS78  = GND
  DQ23_A  = M_G_CPU1_SA_DQ<23>
  VSS79  = GND
  DQ26_A  = M_G_CPU1_SA_DQ<26>
  VSS80  = GND
  DQ27_A  = M_G_CPU1_SA_DQ<27>
  VSS81  = GND
  \dqs8_a_c||tdqs8_a_c\  = M_G_CPU1_SA_DQS_DN<8>
  \dqs8_a_t||tdqs8_a_t\  = M_G_CPU1_SA_DQS_DP<8>
  VSS82  = GND
  DQ30_A  = M_G_CPU1_SA_DQ<30>
  VSS83  = GND
  DQ31_A  = M_G_CPU1_SA_DQ<31>
  VSS84  = GND
  CB2_A  = M_G_CPU1_SA_CB<2>
  VSS85  = GND
  CB3_A  = M_G_CPU1_SA_CB<3>
  VSS86  = GND
  \dqs9_a_c||tdqs9_a_c\  = M_G_CPU1_SA_DQS_DN<9>
  \dqs9_a_t||tdqs9_a_t\  = M_G_CPU1_SA_DQS_DP<9>
  VSS87  = GND
  CB6_A  = M_G_CPU1_SA_CB<6>
  VSS88  = GND
  CB7_A  = M_G_CPU1_SA_CB<7>
  VSS89  = GND
  RESET_N  = RST_M_GH_CPU1_FPGA_N
  VSS90  = GND
  CS1_A_N  = M_G_CPU1_SA_CS_N<1>
  VSS91  = GND
  CA1_A  = M_G_CPU1_SA_CA<1>
  VSS92  = GND
  CA3_A  = M_G_CPU1_SA_CA<3>
  VSS93  = GND
  CA5_A  = M_G_CPU1_SA_CA<5>
  VSS94  = GND
  CK_T  = M_G_CPU1_CLK_DP<0>
  CK_C  = M_G_CPU1_CLK_DN<0>
  VSS95  = GND
  RFU4  = TP_CHG_CPU1_DIMM1_FRU_4
  CA1_B  = M_G_CPU1_SB_CA<1>
  VSS96  = GND
  CA3_B  = M_G_CPU1_SB_CA<3>
  VSS97  = GND
  CA5_B  = M_G_CPU1_SB_CA<5>
  VSS98  = GND
  PAR_B  = M_G_CPU1_SB_PAR
  VSS99  = GND
  CS1_B_N  = M_G_CPU1_SB_CS_N<1>
  VSS100  = GND
  RFU5  = TP_CHG_CPU1_DIMM1_FRU_5
  RFU6  = TP_CHG_CPU1_DIMM1_FRU_6
  VSS101  = GND
  CB6_B  = M_G_CPU1_SB_CB<6>
  VSS102  = GND
  CB7_B  = M_G_CPU1_SB_CB<7>
  VSS103  = GND
  DQS4_B_C  = M_G_CPU1_SB_DQS_DN<4>
  DQS4_B_T  = M_G_CPU1_SB_DQS_DP<4>
  VSS104  = GND
  CB2_B  = M_G_CPU1_SB_CB<2>
  VSS105  = GND
  CB3_B  = M_G_CPU1_SB_CB<3>
  VSS106  = GND
  DQ2_B  = M_G_CPU1_SB_DQ<2>
  VSS107  = GND
  DQ3_B  = M_G_CPU1_SB_DQ<3>
  VSS108  = GND
  \dqs5_b_c||tdqs5_b_c\  = M_G_CPU1_SB_DQS_DN<5>
  \dqs5_b_t||tdqs5_b_t\  = M_G_CPU1_SB_DQS_DP<5>
  VSS109  = GND
  DQ6_B  = M_G_CPU1_SB_DQ<6>
  VSS110  = GND
  DQ7_B  = M_G_CPU1_SB_DQ<7>
  VSS111  = GND
  DQ10_B  = M_G_CPU1_SB_DQ<10>
  VSS112  = GND
  DQ11_B  = M_G_CPU1_SB_DQ<11>
  VSS113  = GND
  \dqs6_b_c||tdqs6_b_c\  = M_G_CPU1_SB_DQS_DN<6>
  \dqs6_b_t||tdqs6_b_t\  = M_G_CPU1_SB_DQS_DP<6>
  VSS114  = GND
  DQ14_B  = M_G_CPU1_SB_DQ<14>
  VSS115  = GND
  DQ15_B  = M_G_CPU1_SB_DQ<15>
  VSS116  = GND
  DQ18_B  = M_G_CPU1_SB_DQ<18>
  VSS117  = GND
  DQ19_B  = M_G_CPU1_SB_DQ<19>
  VSS118  = GND
  \dqs7_b_c||tdqs7_b_c\  = M_G_CPU1_SB_DQS_DN<7>
  \dqs7_b_t||tdqs7_b_t\  = M_G_CPU1_SB_DQS_DP<7>
  VSS119  = GND
  DQ22_B  = M_G_CPU1_SB_DQ<22>
  VSS120  = GND
  DQ23_B  = M_G_CPU1_SB_DQ<23>
  VSS121  = GND
  DQ26_B  = M_G_CPU1_SB_DQ<26>
  VSS122  = GND
  DQ27_B  = M_G_CPU1_SB_DQ<27>
  VSS123  = GND
  \dqs8_b_c||tdqs8_b_c\  = M_G_CPU1_SB_DQS_DN<8>
  \dqs8_b_t||tdqs8_b_t\  = M_G_CPU1_SB_DQS_DP<8>
  VSS124  = GND
  DQ30_B  = M_G_CPU1_SB_DQ<30>
  VSS125  = GND
  DQ31_B  = M_G_CPU1_SB_DQ<31>
  VSS126  = GND
  G1  = GND
  G2  = GND
  G3  = GND

(kicad_pcb
	(version 20260206)
	(generator "pcbnew")
	(generator_version "10.0")
	(general
		(thickness 1.6)
		(legacy_teardrops no)
	)
	(paper "A4")
	(title_block
		(title "03242023_DA0F0TMBIJ0_F0T_Motherboard_J_brd_V01_OCP.brd")
		(comment 1 "Grand Teton / footprint 2874 of 6105 (J29), pads 138-182 of 291")
	)
	(layers
		(0 "F.Cu" signal "TOP")
		(4 "In1.Cu" signal "GND")
		(6 "In2.Cu" signal "IN1")
		(8 "In3.Cu" signal "GND1")
		(10 "In4.Cu" signal "IN2")
		(12 "In5.Cu" signal "GND2")
		(14 "In6.Cu" signal "IN3")
		(16 "In7.Cu" signal "GND3")
		(18 "In8.Cu" signal "VCC")
		(20 "In9.Cu" signal "VCC1")
		(22 "In10.Cu" signal "GND4")
		(24 "In11.Cu" signal "IN4")
		(26 "In12.Cu" signal "GND5")
		(28 "In13.Cu" signal "IN5")
		(30 "In14.Cu" signal "GND6")
		(32 "In15.Cu" signal "IN6")
		(34 "In16.Cu" signal "GND7")
		(2 "B.Cu" signal "BOTTOM")
		(9 "F.Adhes" user "F.Adhesive")
		(11 "B.Adhes" user "B.Adhesive")
		(13 "F.Paste" user "Package Geometry/Pastemask Top")
		(15 "B.Paste" user "Package Geometry/Pastemask Bottom")
		(5 "F.SilkS" user "Ref Des/Silkscreen Top")
		(7 "B.SilkS" user "Ref Des/Silkscreen Bottom")
		(1 "F.Mask" user "Board Geometry/Soldermask Top")
		(3 "B.Mask" user "Board Geometry/Soldermask Bottom")
		(17 "Dwgs.User" user "User.Drawings")
		(19 "Cmts.User" user "User.Comments")
		(21 "Eco1.User" user "User.Eco1")
		(23 "Eco2.User" user "User.Eco2")
		(25 "Edge.Cuts" user "Board Geometry/Outline")
		(27 "Margin" user)
		(31 "F.CrtYd" user "Package Geometry/Place Bound Top")
		(29 "B.CrtYd" user "Package Geometry/Place Bound Bottom")
		(35 "F.Fab" user "Ref Des/Assembly Top")
		(33 "B.Fab" user "Ref Des/Assembly Bottom")
	)
	(footprint ""
		(layer "F.Cu")
		(at 198.58228 -258.091686)
		(property "Reference" "J29"
			(at -3.683 -81.702148 0)
			(unlocked yes)
			(layer "F.SilkS")
			(effects
				(font
					(size 0.7874 0.5842)
					(thickness 0.1524)
				)
				(justify left)
			)
		)
		(property "Value" ""
			(at 0 0 0)
			(layer "F.Fab")
			(effects
				(font
					(size 1.27 1.27)
				)
			)
		)
		(duplicate_pad_numbers_are_jumpers no)
		(pad "138" smd rect
			(at -2.050034 58.224928 270)
			(size 0.519938 1.4986)
			(layers "F.Cu" "F.Mask" "F.Paste")
			(net "M_G_CPU1_SB_DQS_DN<3>")
		)
		(pad "139" smd rect
			(at -2.050034 59.075066 270)
			(size 0.519938 1.4986)
			(layers "F.Cu" "F.Mask" "F.Paste")
			(net "GND")
		)
		(pad "140" smd rect
			(at -2.050034 59.92495 270)
			(size 0.519938 1.4986)
			(layers "F.Cu" "F.Mask" "F.Paste")
			(net "M_G_CPU1_SB_DQ<28>")
		)
		(pad "141" smd rect
			(at -2.050034 60.775088 270)
			(size 0.519938 1.4986)
			(layers "F.Cu" "F.Mask" "F.Paste")
			(net "GND")
		)
		(pad "142" smd rect
			(at -2.050034 61.624972 270)
			(size 0.519938 1.4986)
			(layers "F.Cu" "F.Mask" "F.Paste")
			(net "M_G_CPU1_SB_DQ<29>")
		)
		(pad "143" smd rect
			(at -2.050034 62.47511 270)
			(size 0.519938 1.4986)
			(layers "F.Cu" "F.Mask" "F.Paste")
			(net "GND")
		)
		(pad "144" smd rect
			(at -2.050034 63.324994 270)
			(size 0.519938 1.4986)
			(layers "F.Cu" "F.Mask" "F.Paste")
			(net "TP_CHG_CPU1_DIMM1_FRU_1")
		)
		(pad "145" smd rect
			(at 2.050034 -63.324994 270)
			(size 0.519938 1.4986)
			(layers "F.Cu" "F.Mask" "F.Paste")
			(net "P12V_S3_AUX_CPU1_NVDIMM")
		)
		(pad "146" smd rect
			(at 2.050034 -62.47511 270)
			(size 0.519938 1.4986)
			(layers "F.Cu" "F.Mask" "F.Paste")
			(net "P12V_S3_AUX_CPU1_NVDIMM")
		)
		(pad "147" smd rect
			(at 2.050034 -61.624972 270)
			(size 0.519938 1.4986)
			(layers "F.Cu" "F.Mask" "F.Paste")
			(net "PWRGD_CHG_CPU1_DIMM1")
		)
		(pad "148" smd rect
			(at 2.050034 -60.775088 270)
			(size 0.519938 1.4986)
			(layers "F.Cu" "F.Mask" "F.Paste")
			(net "PD_CHG_CPU1_DIMM1_SAA")
		)
		(pad "149" smd rect
			(at 2.050034 -59.92495 270)
			(size 0.519938 1.4986)
			(layers "F.Cu" "F.Mask" "F.Paste")
			(net "TP_CHG_CPU1_DIMM1_FRU_2")
		)
		(pad "150" smd rect
			(at 2.050034 -59.075066 270)
			(size 0.519938 1.4986)
			(layers "F.Cu" "F.Mask" "F.Paste")
			(net "TP_CHG_CPU1_DIMM1_FRU_3")
		)
		(pad "151" smd rect
			(at 2.050034 -58.224928 270)
			(size 0.519938 1.4986)
			(layers "F.Cu" "F.Mask" "F.Paste")
			(net "GND")
		)
		(pad "152" smd rect
			(at 2.050034 -57.375044 270)
			(size 0.519938 1.4986)
			(layers "F.Cu" "F.Mask" "F.Paste")
			(net "M_G_CPU1_SA_DQ<2>")
		)
		(pad "153" smd rect
			(at 2.050034 -56.524906 270)
			(size 0.519938 1.4986)
			(layers "F.Cu" "F.Mask" "F.Paste")
			(net "GND")
		)
		(pad "154" smd rect
			(at 2.050034 -55.675022 270)
			(size 0.519938 1.4986)
			(layers "F.Cu" "F.Mask" "F.Paste")
			(net "M_G_CPU1_SA_DQ<3>")
		)
		(pad "155" smd rect
			(at 2.050034 -54.824884 270)
			(size 0.519938 1.4986)
			(layers "F.Cu" "F.Mask" "F.Paste")
			(net "GND")
		)
		(pad "156" smd rect
			(at 2.050034 -53.975 270)
			(size 0.519938 1.4986)
			(layers "F.Cu" "F.Mask" "F.Paste")
			(net "M_G_CPU1_SA_DQS_DN<5>")
		)
		(pad "157" smd rect
			(at 2.050034 -53.125116 270)
			(size 0.519938 1.4986)
			(layers "F.Cu" "F.Mask" "F.Paste")
			(net "M_G_CPU1_SA_DQS_DP<5>")
		)
		(pad "158" smd rect
			(at 2.050034 -52.274978 270)
			(size 0.519938 1.4986)
			(layers "F.Cu" "F.Mask" "F.Paste")
			(net "GND")
		)
		(pad "159" smd rect
			(at 2.050034 -51.425094 270)
			(size 0.519938 1.4986)
			(layers "F.Cu" "F.Mask" "F.Paste")
			(net "M_G_CPU1_SA_DQ<6>")
		)
		(pad "160" smd rect
			(at 2.050034 -50.574956 270)
			(size 0.519938 1.4986)
			(layers "F.Cu" "F.Mask" "F.Paste")
			(net "GND")
		)
		(pad "161" smd rect
			(at 2.050034 -49.725072 270)
			(size 0.519938 1.4986)
			(layers "F.Cu" "F.Mask" "F.Paste")
			(net "M_G_CPU1_SA_DQ<7>")
		)
		(pad "162" smd rect
			(at 2.050034 -48.874934 270)
			(size 0.519938 1.4986)
			(layers "F.Cu" "F.Mask" "F.Paste")
			(net "GND")
		)
		(pad "163" smd rect
			(at 2.050034 -48.02505 270)
			(size 0.519938 1.4986)
			(layers "F.Cu" "F.Mask" "F.Paste")
			(net "M_G_CPU1_SA_DQ<10>")
		)
		(pad "164" smd rect
			(at 2.050034 -47.174912 270)
			(size 0.519938 1.4986)
			(layers "F.Cu" "F.Mask" "F.Paste")
			(net "GND")
		)
		(pad "165" smd rect
			(at 2.050034 -46.325028 270)
			(size 0.519938 1.4986)
			(layers "F.Cu" "F.Mask" "F.Paste")
			(net "M_G_CPU1_SA_DQ<11>")
		)
		(pad "166" smd rect
			(at 2.050034 -45.47489 270)
			(size 0.519938 1.4986)
			(layers "F.Cu" "F.Mask" "F.Paste")
			(net "GND")
		)
		(pad "167" smd rect
			(at 2.050034 -44.625006 270)
			(size 0.519938 1.4986)
			(layers "F.Cu" "F.Mask" "F.Paste")
			(net "M_G_CPU1_SA_DQS_DN<6>")
		)
		(pad "168" smd rect
			(at 2.050034 -43.775122 270)
			(size 0.519938 1.4986)
			(layers "F.Cu" "F.Mask" "F.Paste")
			(net "M_G_CPU1_SA_DQS_DP<6>")
		)
		(pad "169" smd rect
			(at 2.050034 -42.924984 270)
			(size 0.519938 1.4986)
			(layers "F.Cu" "F.Mask" "F.Paste")
			(net "GND")
		)
		(pad "170" smd rect
			(at 2.050034 -42.0751 270)
			(size 0.519938 1.4986)
			(layers "F.Cu" "F.Mask" "F.Paste")
			(net "M_G_CPU1_SA_DQ<14>")
		)
		(pad "171" smd rect
			(at 2.050034 -41.224962 270)
			(size 0.519938 1.4986)
			(layers "F.Cu" "F.Mask" "F.Paste")
			(net "GND")
		)
		(pad "172" smd rect
			(at 2.050034 -40.375078 270)
			(size 0.519938 1.4986)
			(layers "F.Cu" "F.Mask" "F.Paste")
			(net "M_G_CPU1_SA_DQ<15>")
		)
		(pad "173" smd rect
			(at 2.050034 -39.52494 270)
			(size 0.519938 1.4986)
			(layers "F.Cu" "F.Mask" "F.Paste")
			(net "GND")
		)
		(pad "174" smd rect
			(at 2.050034 -38.675056 270)
			(size 0.519938 1.4986)
			(layers "F.Cu" "F.Mask" "F.Paste")
			(net "M_G_CPU1_SA_DQ<18>")
		)
		(pad "175" smd rect
			(at 2.050034 -37.824918 270)
			(size 0.519938 1.4986)
			(layers "F.Cu" "F.Mask" "F.Paste")
			(net "GND")
		)
		(pad "176" smd rect
			(at 2.050034 -36.975034 270)
			(size 0.519938 1.4986)
			(layers "F.Cu" "F.Mask" "F.Paste")
			(net "M_G_CPU1_SA_DQ<19>")
		)
		(pad "177" smd rect
			(at 2.050034 -36.124896 270)
			(size 0.519938 1.4986)
			(layers "F.Cu" "F.Mask" "F.Paste")
			(net "GND")
		)
		(pad "178" smd rect
			(at 2.050034 -35.275012 270)
			(size 0.519938 1.4986)
			(layers "F.Cu" "F.Mask" "F.Paste")
			(net "M_G_CPU1_SA_DQS_DN<7>")
		)
		(pad "179" smd rect
			(at 2.050034 -34.425128 270)
			(size 0.519938 1.4986)
			(layers "F.Cu" "F.Mask" "F.Paste")
			(net "M_G_CPU1_SA_DQS_DP<7>")
		)
		(pad "180" smd rect
			(at 2.050034 -33.57499 270)
			(size 0.519938 1.4986)
			(layers "F.Cu" "F.Mask" "F.Paste")
			(net "GND")
		)
		(pad "181" smd rect
			(at 2.050034 -32.725106 270)
			(size 0.519938 1.4986)
			(layers "F.Cu" "F.Mask" "F.Paste")
			(net "M_G_CPU1_SA_DQ<22>")
		)
		(pad "182" smd rect
			(at 2.050034 -31.874968 270)
			(size 0.519938 1.4986)
			(layers "F.Cu" "F.Mask" "F.Paste")
			(net "GND")
		)
	)
)
